FILE_TYPE = CONNECTIVITY;
{Allegro Design Entry HDL 17.4-2019 S026 (4007227) 1/17/2022}
"PAGE_NUMBER" = 52;
0"NC";
1"P5E_CPU1_P3_RX_DN<15:0>";
2"P5E_CPU1_P3_RX_DP<15:0>";
3"P5E_CPU1_P3_TX_DN<15:0>";
4"P5E_CPU1_P3_TX_DP<15:0>";
5"P5E_CPU1_P2_TX_DN<15:0>";
6"P5E_CPU1_P2_TX_DP<15:0>";
7"P5E_CPU1_P2_RX_DP<15:0>";
8"P5E_CPU1_P2_RX_DN<15:0>";
9"P5E_CPU1_P3_TX_DN<1>";
10"P5E_CPU1_P3_TX_DN<3>";
11"P5E_CPU1_P2_RX_DN<15>";
12"P5E_CPU1_P2_RX_DN<13>";
13"P5E_CPU1_P2_RX_DP<14>";
14"P5E_CPU1_P2_RX_DN<14>";
15"P5E_CPU1_P2_RX_DP<15>";
16"P5E_CPU1_P3_RX_DP<0>";
17"P5E_CPU1_P3_RX_DP<1>";
18"P5E_CPU1_P3_RX_DP<2>";
19"P5E_CPU1_P3_RX_DN<2>";
20"P5E_CPU1_P3_RX_DP<3>";
21"P5E_CPU1_P3_RX_DN<1>";
22"P5E_CPU1_P3_RX_DN<0>";
23"P5E_CPU1_P3_TX_DN<5>";
24"P5E_CPU1_P3_TX_DP<6>";
25"P5E_CPU1_P3_TX_DN<6>";
26"P5E_CPU1_P3_TX_DP<0>";
27"P5E_CPU1_P3_TX_DN<0>";
28"P5E_CPU1_P3_TX_DP<1>";
29"P5E_CPU1_P3_TX_DN<4>";
30"P5E_CPU1_P3_TX_DP<5>";
31"P5E_CPU1_P3_TX_DP<7>";
32"P5E_CPU1_P2_TX_DP<15>";
33"P5E_CPU1_P2_TX_DN<15>";
34"P5E_CPU1_P2_TX_DN<2>";
35"P5E_CPU1_P2_TX_DP<2>";
36"P5E_CPU1_P2_TX_DN<1>";
37"P5E_CPU1_P2_TX_DP<1>";
38"P5E_CPU1_P2_TX_DN<0>";
39"P5E_CPU1_P2_TX_DP<0>";
40"P5E_CPU1_P2_RX_DN<0>";
41"P5E_CPU1_P2_RX_DN<12>";
42"P5E_CPU1_P2_RX_DN<11>";
43"P5E_CPU1_P2_RX_DN<10>";
44"P5E_CPU1_P2_RX_DN<9>";
45"P5E_CPU1_P2_RX_DN<8>";
46"P5E_CPU1_P2_RX_DN<7>";
47"P5E_CPU1_P2_RX_DN<6>";
48"P5E_CPU1_P2_RX_DN<5>";
49"P5E_CPU1_P2_RX_DN<4>";
50"P5E_CPU1_P2_RX_DN<3>";
51"P5E_CPU1_P2_RX_DN<2>";
52"P5E_CPU1_P2_RX_DN<1>";
53"P5E_CPU1_P2_RX_DP<13>";
54"P5E_CPU1_P2_RX_DP<12>";
55"P5E_CPU1_P2_RX_DP<11>";
56"P5E_CPU1_P2_RX_DP<10>";
57"P5E_CPU1_P2_RX_DP<9>";
58"P5E_CPU1_P2_RX_DP<8>";
59"P5E_CPU1_P2_RX_DP<7>";
60"P5E_CPU1_P2_RX_DP<6>";
61"P5E_CPU1_P2_RX_DP<5>";
62"P5E_CPU1_P2_RX_DP<4>";
63"P5E_CPU1_P2_RX_DP<3>";
64"P5E_CPU1_P2_RX_DP<2>";
65"P5E_CPU1_P2_RX_DP<1>";
66"P5E_CPU1_P2_RX_DP<0>";
67"P5E_CPU1_P2_TX_DP<3>";
68"P5E_CPU1_P2_TX_DN<3>";
69"P5E_CPU1_P2_TX_DN<9>";
70"P5E_CPU1_P2_TX_DP<11>";
71"P5E_CPU1_P2_TX_DN<10>";
72"P5E_CPU1_P2_TX_DP<4>";
73"P5E_CPU1_P2_TX_DP<5>";
74"P5E_CPU1_P2_TX_DN<4>";
75"P5E_CPU1_P2_TX_DP<8>";
76"P5E_CPU1_P2_TX_DN<8>";
77"P5E_CPU1_P2_TX_DP<9>";
78"P5E_CPU1_P2_TX_DP<10>";
79"P5E_CPU1_P2_TX_DN<11>";
80"P5E_CPU1_P2_TX_DP<12>";
81"P5E_CPU1_P2_TX_DN<12>";
82"P5E_CPU1_P2_TX_DP<13>";
83"P5E_CPU1_P2_TX_DN<13>";
84"P5E_CPU1_P2_TX_DP<14>";
85"P5E_CPU1_P2_TX_DN<14>";
86"P5E_CPU1_P2_TX_DP<6>";
87"P5E_CPU1_P2_TX_DP<7>";
88"P5E_CPU1_P2_TX_DN<5>";
89"P5E_CPU1_P2_TX_DN<6>";
90"P5E_CPU1_P2_TX_DN<7>";
91"P5E_CPU1_P3_TX_DP<2>";
92"P5E_CPU1_P3_TX_DN<2>";
93"P5E_CPU1_P3_TX_DP<3>";
94"P5E_CPU1_P3_TX_DP<4>";
95"P5E_CPU1_P3_TX_DN<7>";
96"P5E_CPU1_P3_TX_DP<8>";
97"P5E_CPU1_P3_TX_DN<8>";
98"P5E_CPU1_P3_TX_DP<9>";
99"P5E_CPU1_P3_TX_DN<9>";
100"P5E_CPU1_P3_TX_DP<10>";
101"P5E_CPU1_P3_TX_DN<10>";
102"P5E_CPU1_P3_TX_DP<11>";
103"P5E_CPU1_P3_TX_DN<11>";
104"P5E_CPU1_P3_TX_DP<12>";
105"P5E_CPU1_P3_TX_DN<12>";
106"P5E_CPU1_P3_TX_DP<13>";
107"P5E_CPU1_P3_TX_DN<13>";
108"P5E_CPU1_P3_TX_DP<14>";
109"P5E_CPU1_P3_TX_DN<14>";
110"P5E_CPU1_P3_TX_DP<15>";
111"P5E_CPU1_P3_TX_DN<15>";
112"P5E_CPU1_P3_RX_DN<3>";
113"P5E_CPU1_P3_RX_DP<4>";
114"P5E_CPU1_P3_RX_DN<4>";
115"P5E_CPU1_P3_RX_DP<5>";
116"P5E_CPU1_P3_RX_DN<5>";
117"P5E_CPU1_P3_RX_DP<6>";
118"P5E_CPU1_P3_RX_DN<6>";
119"P5E_CPU1_P3_RX_DP<7>";
120"P5E_CPU1_P3_RX_DN<7>";
121"P5E_CPU1_P3_RX_DP<8>";
122"P5E_CPU1_P3_RX_DN<8>";
123"P5E_CPU1_P3_RX_DP<9>";
124"P5E_CPU1_P3_RX_DN<9>";
125"P5E_CPU1_P3_RX_DP<10>";
126"P5E_CPU1_P3_RX_DN<10>";
127"P5E_CPU1_P3_RX_DP<11>";
128"P5E_CPU1_P3_RX_DN<11>";
129"P5E_CPU1_P3_RX_DP<12>";
130"P5E_CPU1_P3_RX_DN<12>";
131"P5E_CPU1_P3_RX_DP<13>";
132"P5E_CPU1_P3_RX_DN<13>";
133"P5E_CPU1_P3_RX_DP<14>";
134"P5E_CPU1_P3_RX_DN<14>";
135"P5E_CPU1_P3_RX_DP<15>";
136"P5E_CPU1_P3_RX_DN<15>";
%"GENOA_SP5"
"18","(-4625,2350)","0","pure_quanta","I147";
;
LOCATION"U26"
$SEC"18"
CDS_SEC"18"
MATERIAL"IO"
VALUE"SOCKET6096_13568-001"
PART_TYPE"SMLF"
CDS_LIB"pure_quanta"
CDS_LMAN_SYM_OUTLINE"-600,950,600,-950"
NEEDS_NO_SIZE"TRUE"
PART_NUMBER"DGA^6000030";
"P3_TXN15"
$PN"CE23"111;
"P3_TXP15"
$PN"CE24"110;
"P3_TXN14"
$PN"CG23"109;
"P3_TXP14"
$PN"CG24"108;
"P3_TXN13"
$PN"CC23"107;
"P3_TXP13"
$PN"CC24"106;
"P3_TXN12"
$PN"CE26"105;
"P3_TXP12"
$PN"CE27"104;
"P3_TXN11"
$PN"CG26"103;
"P3_TXP11"
$PN"CG27"102;
"P3_TXN10"
$PN"CC26"101;
"P3_TXP10"
$PN"CC27"100;
"P3_TXN9"
$PN"CE29"99;
"P3_TXP9"
$PN"CE30"98;
"P3_TXN8"
$PN"CG29"97;
"P3_TXP8"
$PN"CG30"96;
"P3_TXN7"
$PN"CC29"95;
"P3_TXP7"
$PN"CC30"31;
"P3_TXN6"
$PN"CE32"25;
"P3_TXP6"
$PN"CE33"24;
"P3_TXN5"
$PN"CG32"23;
"P3_TXP5"
$PN"CG33"30;
"P3_TXN4"
$PN"CJ32"29;
"P3_TXP4"
$PN"CJ33"94;
"P3_TXN3"
$PN"CC32"10;
"P3_TXP3"
$PN"CC33"93;
"P3_TXN2"
$PN"CH35"92;
"P3_TXP2"
$PN"CH36"91;
"P3_TXN1"
$PN"CF35"9;
"P3_TXP1"
$PN"CF36"28;
"P3_TXN0"
$PN"CD35"27;
"P3_TXP0"
$PN"CD36"26;
"P3_RXN15"
$PN"CU24"136;
"P3_RXP15"
$PN"CU23"135;
"P3_RXN14"
$PN"DA24"134;
"P3_RXP14"
$PN"DA23"133;
"P3_RXN13"
$PN"DC24"132;
"P3_RXP13"
$PN"DC23"131;
"P3_RXN12"
$PN"CW24"130;
"P3_RXP12"
$PN"CW23"129;
"P3_RXN11"
$PN"DA27"128;
"P3_RXP11"
$PN"DA26"127;
"P3_RXN10"
$PN"DC27"126;
"P3_RXP10"
$PN"DC26"125;
"P3_RXN9"
$PN"CW27"124;
"P3_RXP9"
$PN"CW26"123;
"P3_RXN8"
$PN"DA30"122;
"P3_RXP8"
$PN"DA29"121;
"P3_RXN7"
$PN"DC30"120;
"P3_RXP7"
$PN"DC29"119;
"P3_RXN6"
$PN"CW30"118;
"P3_RXP6"
$PN"CW29"117;
"P3_RXN5"
$PN"DA33"116;
"P3_RXP5"
$PN"DA32"115;
"P3_RXN4"
$PN"DC33"114;
"P3_RXP4"
$PN"DC32"113;
"P3_RXN3"
$PN"CW33"112;
"P3_RXP3"
$PN"CW32"20;
"P3_RXN2"
$PN"DB36"19;
"P3_RXP2"
$PN"DB35"18;
"P3_RXN1"
$PN"CY36"21;
"P3_RXP1"
$PN"CY35"17;
"P3_RXN0"
$PN"CV36"22;
"P3_RXP0"
$PN"CV35"16;
%"GENOA_SP5"
"17","(-4625,4850)","0","pure_quanta","I148";
;
LOCATION"U26"
$SEC"17"
CDS_SEC"17"
MATERIAL"IO"
VALUE"SOCKET6096_13568-001"
PART_TYPE"SMLF"
CDS_LIB"pure_quanta"
CDS_LMAN_SYM_OUTLINE"-600,950,600,-950"
NEEDS_NO_SIZE"TRUE"
PART_NUMBER"DGA^6000030";
"P2_RXN7"
$PN"CU30"46;
"P2_RXN6"
$PN"CN30"47;
"P2_RXN5"
$PN"CR33"48;
"P2_RXP7"
$PN"CU29"59;
"P2_TXN7"
$PN"BU29"90;
"P2_RXN4"
$PN"CU33"49;
"P2_RXP6"
$PN"CN29"60;
"P2_TXN6"
$PN"BW32"89;
"P2_RXN3"
$PN"CN33"50;
"P2_RXP5"
$PN"CR32"61;
"P2_TXN5"
$PN"CA32"88;
"P2_TXP7"
$PN"BU30"87;
"P2_RXN2"
$PN"CT36"51;
"P2_RXP4"
$PN"CU32"62;
"P2_TXN4"
$PN"BU32"74;
"P2_TXP6"
$PN"BW33"86;
"P2_RXN1"
$PN"CP36"52;
"P2_RXP3"
$PN"CN32"63;
"P2_TXN3"
$PN"BY35"68;
"P2_TXP5"
$PN"CA33"73;
"P2_RXN0"
$PN"CM36"40;
"P2_RXP2"
$PN"CT35"64;
"P2_TXN2"
$PN"CB35"34;
"P2_TXP4"
$PN"BU33"72;
"P2_RXP1"
$PN"CP35"65;
"P2_TXN1"
$PN"BV35"36;
"P2_TXP3"
$PN"BY36"67;
"P2_RXP0"
$PN"CM35"66;
"P2_TXN0"
$PN"BT35"38;
"P2_TXP2"
$PN"CB36"35;
"P2_TXP1"
$PN"BV36"37;
"P2_TXP0"
$PN"BT36"39;
"P2_TXN15"
$PN"BW23"33;
"P2_TXP15"
$PN"BW24"32;
"P2_TXN14"
$PN"CA23"85;
"P2_TXP14"
$PN"CA24"84;
"P2_TXN13"
$PN"BU23"83;
"P2_TXP13"
$PN"BU24"82;
"P2_TXN12"
$PN"BW26"81;
"P2_TXP12"
$PN"BW27"80;
"P2_TXN11"
$PN"CA26"79;
"P2_TXP11"
$PN"CA27"70;
"P2_TXN10"
$PN"BU26"71;
"P2_TXP10"
$PN"BU27"78;
"P2_TXN9"
$PN"BW29"69;
"P2_TXP9"
$PN"BW30"77;
"P2_TXN8"
$PN"CA29"76;
"P2_TXP8"
$PN"CA30"75;
"P2_RXN15"
$PN"CN24"11;
"P2_RXP15"
$PN"CN23"15;
"P2_RXN14"
$PN"CR24"14;
"P2_RXP14"
$PN"CR23"13;
"P2_RXN13"
$PN"CL24"12;
"P2_RXP13"
$PN"CL23"53;
"P2_RXN12"
$PN"CN27"41;
"P2_RXP12"
$PN"CN26"54;
"P2_RXN11"
$PN"CR27"42;
"P2_RXP11"
$PN"CR26"55;
"P2_RXN10"
$PN"CU27"43;
"P2_RXP10"
$PN"CU26"56;
"P2_RXN9"
$PN"CL27"44;
"P2_RXP9"
$PN"CL26"57;
"P2_RXN8"
$PN"CR30"45;
"P2_RXP8"
$PN"CR29"58;
%"TAP"
"6","(-3450,5650)","2","mstr_standard","I151";
;
CDS_LIB"mstr_standard"
BOM_COST"IO_SLOT"
ROOM"RISER1"
BODY_TYPE"PLUMBING"
HDL_TAP"TRUE";
"B \NAC \NWC"6;
"S \NAC"
BN"0"39;
%"TAP"
"6","(-3300,5500)","2","mstr_standard","I152";
;
CDS_LIB"mstr_standard"
BOM_COST"IO_SLOT"
ROOM"RISER1"
BODY_TYPE"PLUMBING"
HDL_TAP"TRUE";
"B \NAC \NWC"5;
"S \NAC"
BN"1"36;
%"TAP"
"6","(-3300,5400)","2","standard","I153";
;
CDS_LIB"standard"
BOM_COST"IO_SLOT"
ROOM"RISER1"
BODY_TYPE"PLUMBING"
HDL_TAP"TRUE";
"B \NAC \NWC"5;
"S \NAC"
BN"2"34;
%"TAP"
"6","(-3300,5600)","2","mstr_standard","I154";
;
BOM_COST"IO_SLOT"
CDS_LIB"mstr_standard"
ROOM"RISER1"
BODY_TYPE"PLUMBING"
HDL_TAP"TRUE";
"B \NAC \NWC"5;
"S \NAC"
BN"0"38;
%"TAP"
"6","(-3450,5550)","2","mstr_standard","I155";
;
CDS_LIB"mstr_standard"
BOM_COST"IO_SLOT"
ROOM"RISER1"
BODY_TYPE"PLUMBING"
HDL_TAP"TRUE";
"B \NAC \NWC"6;
"S \NAC"
BN"1"37;
%"TAP"
"6","(-3450,5450)","2","standard","I156";
;
CDS_LIB"standard"
BOM_COST"IO_SLOT"
ROOM"RISER1"
BODY_TYPE"PLUMBING"
HDL_TAP"TRUE";
"B \NAC \NWC"6;
"S \NAC"
BN"2"35;
%"TAP"
"6","(-3300,5300)","2","standard","I157";
;
CDS_LIB"standard"
BOM_COST"IO_SLOT"
ROOM"RISER1"
BODY_TYPE"PLUMBING"
HDL_TAP"TRUE";
"B \NAC \NWC"5;
"S \NAC"
BN"3"68;
%"TAP"
"6","(-3300,5200)","2","standard","I158";
;
CDS_LIB"standard"
BOM_COST"IO_SLOT"
ROOM"RISER1"
BODY_TYPE"PLUMBING"
HDL_TAP"TRUE";
"B \NAC \NWC"5;
"S \NAC"
BN"4"74;
%"TAP"
"6","(-3450,5250)","2","standard","I159";
;
CDS_LIB"standard"
BOM_COST"IO_SLOT"
ROOM"RISER1"
BODY_TYPE"PLUMBING"
HDL_TAP"TRUE";
"B \NAC \NWC"6;
"S \NAC"
BN"4"72;
%"TAP"
"6","(-3450,5350)","2","standard","I160";
;
CDS_LIB"standard"
BOM_COST"IO_SLOT"
ROOM"RISER1"
BODY_TYPE"PLUMBING"
HDL_TAP"TRUE";
"B \NAC \NWC"6;
"S \NAC"
BN"3"67;
%"TAP"
"6","(-3450,5150)","2","standard","I161";
;
CDS_LIB"standard"
BOM_COST"IO_SLOT"
ROOM"RISER1"
BODY_TYPE"PLUMBING"
HDL_TAP"TRUE";
"B \NAC \NWC"6;
"S \NAC"
BN"5"73;
%"TAP"
"6","(-3300,5000)","2","standard","I162";
;
CDS_LIB"standard"
BOM_COST"IO_SLOT"
ROOM"RISER1"
BODY_TYPE"PLUMBING"
HDL_TAP"TRUE";
"B \NAC \NWC"5;
"S \NAC"
BN"6"89;
%"TAP"
"6","(-3300,5100)","2","standard","I163";
;
CDS_LIB"standard"
BOM_COST"IO_SLOT"
ROOM"RISER1"
BODY_TYPE"PLUMBING"
HDL_TAP"TRUE";
"B \NAC \NWC"5;
"S \NAC"
BN"5"88;
%"TAP"
"6","(-3300,4900)","2","standard","I164";
;
CDS_LIB"standard"
BOM_COST"IO_SLOT"
ROOM"RISER1"
BODY_TYPE"PLUMBING"
HDL_TAP"TRUE";
"B \NAC \NWC"5;
"S \NAC"
BN"7"90;
%"TAP"
"6","(-3450,4950)","2","standard","I165";
;
CDS_LIB"standard"
BOM_COST"IO_SLOT"
ROOM"RISER1"
BODY_TYPE"PLUMBING"
HDL_TAP"TRUE";
"B \NAC \NWC"6;
"S \NAC"
BN"7"87;
%"TAP"
"6","(-3450,5050)","2","standard","I166";
;
CDS_LIB"standard"
BOM_COST"IO_SLOT"
ROOM"RISER1"
BODY_TYPE"PLUMBING"
HDL_TAP"TRUE";
"B \NAC \NWC"6;
"S \NAC"
BN"6"86;
%"TAP"
"6","(-3300,4700)","2","standard","I167";
;
CDS_LIB"standard"
BOM_COST"IO_SLOT"
ROOM"RISER1"
BODY_TYPE"PLUMBING"
HDL_TAP"TRUE";
"B \NAC \NWC"5;
"S \NAC"
BN"9"69;
%"TAP"
"6","(-3300,4800)","2","standard","I168";
;
CDS_LIB"standard"
BOM_COST"IO_SLOT"
ROOM"RISER1"
BODY_TYPE"PLUMBING"
HDL_TAP"TRUE";
"B \NAC \NWC"5;
"S \NAC"
BN"8"76;
%"TAP"
"6","(-3450,4850)","2","standard","I169";
;
CDS_LIB"standard"
BOM_COST"IO_SLOT"
ROOM"RISER1"
BODY_TYPE"PLUMBING"
HDL_TAP"TRUE";
"B \NAC \NWC"6;
"S \NAC"
BN"8"75;
%"TAP"
"6","(-3450,4750)","2","standard","I170";
;
CDS_LIB"standard"
BOM_COST"IO_SLOT"
ROOM"RISER1"
BODY_TYPE"PLUMBING"
HDL_TAP"TRUE";
"B \NAC \NWC"6;
"S \NAC"
BN"9"77;
%"TAP"
"6","(-3450,4650)","2","standard","I171";
;
CDS_LIB"standard"
BOM_COST"IO_SLOT"
ROOM"RISER1"
BODY_TYPE"PLUMBING"
HDL_TAP"TRUE";
"B \NAC \NWC"6;
"S \NAC"
BN"10"78;
%"TAP"
"6","(-3300,4600)","2","standard","I172";
;
CDS_LIB"standard"
BOM_COST"IO_SLOT"
ROOM"RISER1"
BODY_TYPE"PLUMBING"
HDL_TAP"TRUE";
"B \NAC \NWC"5;
"S \NAC"
BN"10"71;
%"TAP"
"6","(-3300,4500)","2","standard","I173";
;
CDS_LIB"standard"
BOM_COST"IO_SLOT"
ROOM"RISER1"
BODY_TYPE"PLUMBING"
HDL_TAP"TRUE";
"B \NAC \NWC"5;
"S \NAC"
BN"11"79;
%"TAP"
"6","(-3300,4400)","2","standard","I174";
;
CDS_LIB"standard"
BOM_COST"IO_SLOT"
ROOM"RISER1"
BODY_TYPE"PLUMBING"
HDL_TAP"TRUE";
"B \NAC \NWC"5;
"S \NAC"
BN"12"81;
%"TAP"
"6","(-3450,4550)","2","standard","I175";
;
CDS_LIB"standard"
BOM_COST"IO_SLOT"
ROOM"RISER1"
BODY_TYPE"PLUMBING"
HDL_TAP"TRUE";
"B \NAC \NWC"6;
"S \NAC"
BN"11"70;
%"TAP"
"6","(-3450,4450)","2","standard","I176";
;
CDS_LIB"standard"
BOM_COST"IO_SLOT"
ROOM"RISER1"
BODY_TYPE"PLUMBING"
HDL_TAP"TRUE";
"B \NAC \NWC"6;
"S \NAC"
BN"12"80;
%"TAP"
"6","(-3300,4200)","2","standard","I177";
;
BOM_COST"IO_SLOT"
CDS_LIB"standard"
ROOM"RISER1"
BODY_TYPE"PLUMBING"
HDL_TAP"TRUE";
"B \NAC \NWC"5;
"S \NAC"
BN"14"85;
%"TAP"
"6","(-3300,4100)","2","standard","I178";
;
CDS_LIB"standard"
BOM_COST"IO_SLOT"
ROOM"RISER1"
BODY_TYPE"PLUMBING"
HDL_TAP"TRUE";
"B \NAC \NWC"5;
"S \NAC"
BN"15"33;
%"TAP"
"6","(-3300,4300)","2","standard","I179";
;
CDS_LIB"standard"
BOM_COST"IO_SLOT"
ROOM"RISER1"
BODY_TYPE"PLUMBING"
HDL_TAP"TRUE";
"B \NAC \NWC"5;
"S \NAC"
BN"13"83;
%"TAP"
"6","(-3450,4350)","2","standard","I180";
;
CDS_LIB"standard"
BOM_COST"IO_SLOT"
ROOM"RISER1"
BODY_TYPE"PLUMBING"
HDL_TAP"TRUE";
"B \NAC \NWC"6;
"S \NAC"
BN"13"82;
%"TAP"
"6","(-3450,4250)","2","standard","I181";
;
CDS_LIB"standard"
BOM_COST"IO_SLOT"
ROOM"RISER1"
BODY_TYPE"PLUMBING"
HDL_TAP"TRUE";
"B \NAC \NWC"6;
"S \NAC"
BN"14"84;
%"TAP"
"6","(-3450,4150)","2","standard","I182";
;
CDS_LIB"standard"
BOM_COST"IO_SLOT"
ROOM"RISER1"
BODY_TYPE"PLUMBING"
HDL_TAP"TRUE";
"B \NAC \NWC"6;
"S \NAC"
BN"15"32;
%"TAP"
"6","(-3300,3100)","2","mstr_standard","I185";
;
CDS_LIB"mstr_standard"
BOM_COST"IO_SLOT"
ROOM"RISER1"
BODY_TYPE"PLUMBING"
HDL_TAP"TRUE";
"B \NAC \NWC"3;
"S \NAC"
BN"0"27;
%"TAP"
"6","(-3450,3150)","2","mstr_standard","I186";
;
BOM_COST"IO_SLOT"
CDS_LIB"mstr_standard"
ROOM"RISER1"
BODY_TYPE"PLUMBING"
HDL_TAP"TRUE";
"B \NAC \NWC"4;
"S \NAC"
BN"0"26;
%"TAP"
"6","(-3300,2900)","2","standard","I187";
;
BOM_COST"IO_SLOT"
CDS_LIB"standard"
ROOM"RISER1"
BODY_TYPE"PLUMBING"
HDL_TAP"TRUE";
"B \NAC \NWC"3;
"S \NAC"
BN"2"92;
%"TAP"
"6","(-3300,3000)","2","mstr_standard","I188";
;
BOM_COST"IO_SLOT"
CDS_LIB"mstr_standard"
ROOM"RISER1"
BODY_TYPE"PLUMBING"
HDL_TAP"TRUE";
"B \NAC \NWC"3;
"S \NAC"
BN"1"9;
%"TAP"
"6","(-3450,3050)","2","mstr_standard","I189";
;
BOM_COST"IO_SLOT"
CDS_LIB"mstr_standard"
ROOM"RISER1"
BODY_TYPE"PLUMBING"
HDL_TAP"TRUE";
"B \NAC \NWC"4;
"S \NAC"
BN"1"28;
%"TAP"
"6","(-3450,2950)","2","standard","I190";
;
BOM_COST"IO_SLOT"
CDS_LIB"standard"
ROOM"RISER1"
BODY_TYPE"PLUMBING"
HDL_TAP"TRUE";
"B \NAC \NWC"4;
"S \NAC"
BN"2"91;
%"TAP"
"6","(-3450,2850)","2","standard","I191";
;
BOM_COST"IO_SLOT"
CDS_LIB"standard"
ROOM"RISER1"
BODY_TYPE"PLUMBING"
HDL_TAP"TRUE";
"B \NAC \NWC"4;
"S \NAC"
BN"3"93;
%"TAP"
"6","(-3300,2800)","2","standard","I192";
;
BOM_COST"IO_SLOT"
CDS_LIB"standard"
ROOM"RISER1"
BODY_TYPE"PLUMBING"
HDL_TAP"TRUE";
"B \NAC \NWC"3;
"S \NAC"
BN"3"10;
%"TAP"
"6","(-3300,2700)","2","standard","I193";
;
BOM_COST"IO_SLOT"
CDS_LIB"standard"
ROOM"RISER1"
BODY_TYPE"PLUMBING"
HDL_TAP"TRUE";
"B \NAC \NWC"3;
"S \NAC"
BN"4"29;
%"TAP"
"6","(-3300,2600)","2","standard","I194";
;
BOM_COST"IO_SLOT"
CDS_LIB"standard"
ROOM"RISER1"
BODY_TYPE"PLUMBING"
HDL_TAP"TRUE";
"B \NAC \NWC"3;
"S \NAC"
BN"5"23;
%"TAP"
"6","(-3450,2750)","2","standard","I195";
;
BOM_COST"IO_SLOT"
CDS_LIB"standard"
ROOM"RISER1"
BODY_TYPE"PLUMBING"
HDL_TAP"TRUE";
"B \NAC \NWC"4;
"S \NAC"
BN"4"94;
%"TAP"
"6","(-3450,2650)","2","standard","I196";
;
BOM_COST"IO_SLOT"
CDS_LIB"standard"
ROOM"RISER1"
BODY_TYPE"PLUMBING"
HDL_TAP"TRUE";
"B \NAC \NWC"4;
"S \NAC"
BN"5"30;
%"TAP"
"6","(-3300,2400)","2","standard","I197";
;
BOM_COST"IO_SLOT"
CDS_LIB"standard"
ROOM"RISER1"
BODY_TYPE"PLUMBING"
HDL_TAP"TRUE";
"B \NAC \NWC"3;
"S \NAC"
BN"7"95;
%"TAP"
"6","(-3300,2500)","2","standard","I198";
;
BOM_COST"IO_SLOT"
CDS_LIB"standard"
ROOM"RISER1"
BODY_TYPE"PLUMBING"
HDL_TAP"TRUE";
"B \NAC \NWC"3;
"S \NAC"
BN"6"25;
%"TAP"
"6","(-3450,2550)","2","standard","I199";
;
BOM_COST"IO_SLOT"
CDS_LIB"standard"
ROOM"RISER1"
BODY_TYPE"PLUMBING"
HDL_TAP"TRUE";
"B \NAC \NWC"4;
"S \NAC"
BN"6"24;
%"TAP"
"6","(-3450,2450)","2","standard","I200";
;
BOM_COST"IO_SLOT"
CDS_LIB"standard"
ROOM"RISER1"
BODY_TYPE"PLUMBING"
HDL_TAP"TRUE";
"B \NAC \NWC"4;
"S \NAC"
BN"7"31;
%"TAP"
"6","(-3450,2350)","2","standard","I201";
;
BOM_COST"IO_SLOT"
CDS_LIB"standard"
ROOM"RISER1"
BODY_TYPE"PLUMBING"
HDL_TAP"TRUE";
"B \NAC \NWC"4;
"S \NAC"
BN"8"96;
%"TAP"
"6","(-3300,2300)","2","standard","I202";
;
BOM_COST"IO_SLOT"
CDS_LIB"standard"
ROOM"RISER1"
BODY_TYPE"PLUMBING"
HDL_TAP"TRUE";
"B \NAC \NWC"3;
"S \NAC"
BN"8"97;
%"TAP"
"6","(-3300,2200)","2","standard","I203";
;
BOM_COST"IO_SLOT"
CDS_LIB"standard"
ROOM"RISER1"
BODY_TYPE"PLUMBING"
HDL_TAP"TRUE";
"B \NAC \NWC"3;
"S \NAC"
BN"9"99;
%"TAP"
"6","(-3300,2100)","2","standard","I204";
;
BOM_COST"IO_SLOT"
CDS_LIB"standard"
ROOM"RISER1"
BODY_TYPE"PLUMBING"
HDL_TAP"TRUE";
"B \NAC \NWC"3;
"S \NAC"
BN"10"101;
%"TAP"
"6","(-3450,2250)","2","standard","I205";
;
BOM_COST"IO_SLOT"
CDS_LIB"standard"
ROOM"RISER1"
BODY_TYPE"PLUMBING"
HDL_TAP"TRUE";
"B \NAC \NWC"4;
"S \NAC"
BN"9"98;
%"TAP"
"6","(-3450,2150)","2","standard","I206";
;
BOM_COST"IO_SLOT"
CDS_LIB"standard"
ROOM"RISER1"
BODY_TYPE"PLUMBING"
HDL_TAP"TRUE";
"B \NAC \NWC"4;
"S \NAC"
BN"10"100;
%"TAP"
"6","(-3450,2050)","2","standard","I207";
;
BOM_COST"IO_SLOT"
CDS_LIB"standard"
ROOM"RISER1"
BODY_TYPE"PLUMBING"
HDL_TAP"TRUE";
"B \NAC \NWC"4;
"S \NAC"
BN"11"102;
%"TAP"
"6","(-3300,1800)","2","standard","I208";
;
BOM_COST"IO_SLOT"
CDS_LIB"standard"
ROOM"RISER1"
BODY_TYPE"PLUMBING"
HDL_TAP"TRUE";
"B \NAC \NWC"3;
"S \NAC"
BN"13"107;
%"TAP"
"6","(-3300,1900)","2","standard","I209";
;
BOM_COST"IO_SLOT"
CDS_LIB"standard"
ROOM"RISER1"
BODY_TYPE"PLUMBING"
HDL_TAP"TRUE";
"B \NAC \NWC"3;
"S \NAC"
BN"12"105;
%"TAP"
"6","(-3300,2000)","2","standard","I210";
;
BOM_COST"IO_SLOT"
CDS_LIB"standard"
ROOM"RISER1"
BODY_TYPE"PLUMBING"
HDL_TAP"TRUE";
"B \NAC \NWC"3;
"S \NAC"
BN"11"103;
%"TAP"
"6","(-3450,1950)","2","standard","I211";
;
BOM_COST"IO_SLOT"
CDS_LIB"standard"
ROOM"RISER1"
BODY_TYPE"PLUMBING"
HDL_TAP"TRUE";
"B \NAC \NWC"4;
"S \NAC"
BN"12"104;
%"TAP"
"6","(-3450,1850)","2","standard","I212";
;
BOM_COST"IO_SLOT"
CDS_LIB"standard"
ROOM"RISER1"
BODY_TYPE"PLUMBING"
HDL_TAP"TRUE";
"B \NAC \NWC"4;
"S \NAC"
BN"13"106;
%"TAP"
"6","(-3300,1600)","2","standard","I213";
;
BOM_COST"IO_SLOT"
CDS_LIB"standard"
ROOM"RISER1"
BODY_TYPE"PLUMBING"
HDL_TAP"TRUE";
"B \NAC \NWC"3;
"S \NAC"
BN"15"111;
%"TAP"
"6","(-3300,1700)","2","standard","I214";
;
CDS_LIB"standard"
BOM_COST"IO_SLOT"
ROOM"RISER1"
BODY_TYPE"PLUMBING"
HDL_TAP"TRUE";
"B \NAC \NWC"3;
"S \NAC"
BN"14"109;
%"TAP"
"6","(-3450,1750)","2","standard","I215";
;
BOM_COST"IO_SLOT"
CDS_LIB"standard"
ROOM"RISER1"
BODY_TYPE"PLUMBING"
HDL_TAP"TRUE";
"B \NAC \NWC"4;
"S \NAC"
BN"14"108;
%"TAP"
"6","(-3450,1650)","2","standard","I216";
;
BOM_COST"IO_SLOT"
CDS_LIB"standard"
ROOM"RISER1"
BODY_TYPE"PLUMBING"
HDL_TAP"TRUE";
"B \NAC \NWC"4;
"S \NAC"
BN"15"110;
%"TAP"
"6","(-5875,3150)","0","mstr_standard","I251";
;
CDS_LIB"mstr_standard"
BODY_TYPE"PLUMBING"
HDL_TAP"TRUE";
"B \NAC \NWC"2;
"S \NAC"
BN"0"16;
%"TAP"
"6","(-5875,2950)","0","mstr_standard","I253";
;
CDS_LIB"mstr_standard"
BODY_TYPE"PLUMBING"
HDL_TAP"TRUE";
"B \NAC \NWC"2;
"S \NAC"
BN"2"18;
%"TAP"
"6","(-5875,3050)","0","mstr_standard","I254";
;
CDS_LIB"mstr_standard"
BODY_TYPE"PLUMBING"
HDL_TAP"TRUE";
"B \NAC \NWC"2;
"S \NAC"
BN"1"17;
%"TAP"
"6","(-5875,2850)","0","standard","I255";
;
CDS_LIB"standard"
BODY_TYPE"PLUMBING"
HDL_TAP"TRUE";
"B \NAC \NWC"2;
"S \NAC"
BN"3"20;
%"TAP"
"6","(-5875,2750)","0","standard","I256";
;
CDS_LIB"standard"
BODY_TYPE"PLUMBING"
HDL_TAP"TRUE";
"B \NAC \NWC"2;
"S \NAC"
BN"4"113;
%"TAP"
"6","(-5875,2650)","0","standard","I257";
;
CDS_LIB"standard"
BODY_TYPE"PLUMBING"
HDL_TAP"TRUE";
"B \NAC \NWC"2;
"S \NAC"
BN"5"115;
%"TAP"
"6","(-5875,2550)","0","standard","I263";
;
CDS_LIB"standard"
BODY_TYPE"PLUMBING"
HDL_TAP"TRUE";
"B \NAC \NWC"2;
"S \NAC"
BN"6"117;
%"TAP"
"6","(-5875,2450)","0","mstr_standard","I285";
;
CDS_LIB"mstr_standard"
BODY_TYPE"PLUMBING"
HDL_TAP"TRUE";
"B \NAC \NWC"2;
"S \NAC"
BN"7"119;
%"TAP"
"6","(-5875,2050)","0","standard","I286";
;
CDS_LIB"standard"
BODY_TYPE"PLUMBING"
HDL_TAP"TRUE";
"B \NAC \NWC"2;
"S \NAC"
BN"11"127;
%"TAP"
"6","(-5875,1950)","0","standard","I287";
;
CDS_LIB"standard"
BODY_TYPE"PLUMBING"
HDL_TAP"TRUE";
"B \NAC \NWC"2;
"S \NAC"
BN"12"129;
%"TAP"
"6","(-5875,1850)","0","standard","I288";
;
CDS_LIB"standard"
BODY_TYPE"PLUMBING"
HDL_TAP"TRUE";
"B \NAC \NWC"2;
"S \NAC"
BN"13"131;
%"TAP"
"6","(-5875,2350)","0","mstr_standard","I292";
;
CDS_LIB"mstr_standard"
BODY_TYPE"PLUMBING"
HDL_TAP"TRUE";
"B \NAC \NWC"2;
"S \NAC"
BN"8"121;
%"TAP"
"6","(-5875,2250)","0","mstr_standard","I293";
;
CDS_LIB"mstr_standard"
BODY_TYPE"PLUMBING"
HDL_TAP"TRUE";
"B \NAC \NWC"2;
"S \NAC"
BN"9"123;
%"TAP"
"6","(-5875,2150)","0","standard","I294";
;
CDS_LIB"standard"
BODY_TYPE"PLUMBING"
HDL_TAP"TRUE";
"B \NAC \NWC"2;
"S \NAC"
BN"10"125;
%"TAP"
"6","(-5875,1750)","0","standard","I299";
;
CDS_LIB"standard"
BODY_TYPE"PLUMBING"
HDL_TAP"TRUE";
"B \NAC \NWC"2;
"S \NAC"
BN"14"133;
%"TAP"
"6","(-5875,1650)","0","standard","I302";
;
CDS_LIB"standard"
BODY_TYPE"PLUMBING"
HDL_TAP"TRUE";
"B \NAC \NWC"2;
"S \NAC"
BN"15"135;
%"TAP"
"6","(-6025,3000)","0","mstr_standard","I303";
;
CDS_LIB"mstr_standard"
BODY_TYPE"PLUMBING"
HDL_TAP"TRUE";
"B \NAC \NWC"1;
"S \NAC"
BN"1"21;
%"TAP"
"6","(-6025,3100)","0","mstr_standard","I304";
;
CDS_LIB"mstr_standard"
BODY_TYPE"PLUMBING"
HDL_TAP"TRUE";
"B \NAC \NWC"1;
"S \NAC"
BN"0"22;
%"TAP"
"6","(-6025,2900)","0","standard","I305";
;
CDS_LIB"standard"
BODY_TYPE"PLUMBING"
HDL_TAP"TRUE";
"B \NAC \NWC"1;
"S \NAC"
BN"2"19;
%"TAP"
"6","(-6025,2800)","0","standard","I306";
;
CDS_LIB"standard"
BODY_TYPE"PLUMBING"
HDL_TAP"TRUE";
"B \NAC \NWC"1;
"S \NAC"
BN"3"112;
%"TAP"
"6","(-6025,2700)","0","standard","I307";
;
CDS_LIB"standard"
BODY_TYPE"PLUMBING"
HDL_TAP"TRUE";
"B \NAC \NWC"1;
"S \NAC"
BN"4"114;
%"TAP"
"6","(-6025,2600)","0","standard","I308";
;
CDS_LIB"standard"
BODY_TYPE"PLUMBING"
HDL_TAP"TRUE";
"B \NAC \NWC"1;
"S \NAC"
BN"5"116;
%"TAP"
"6","(-6025,2500)","0","standard","I309";
;
CDS_LIB"standard"
BODY_TYPE"PLUMBING"
HDL_TAP"TRUE";
"B \NAC \NWC"1;
"S \NAC"
BN"6"118;
%"TAP"
"6","(-6025,2400)","0","mstr_standard","I310";
;
CDS_LIB"mstr_standard"
BODY_TYPE"PLUMBING"
HDL_TAP"TRUE";
"B \NAC \NWC"1;
"S \NAC"
BN"7"120;
%"TAP"
"6","(-6025,2200)","0","standard","I311";
;
CDS_LIB"standard"
BODY_TYPE"PLUMBING"
HDL_TAP"TRUE";
"B \NAC \NWC"1;
"S \NAC"
BN"9"124;
%"TAP"
"6","(-6025,2300)","0","mstr_standard","I312";
;
CDS_LIB"mstr_standard"
BODY_TYPE"PLUMBING"
HDL_TAP"TRUE";
"B \NAC \NWC"1;
"S \NAC"
BN"8"122;
%"TAP"
"6","(-6025,2100)","0","standard","I313";
;
CDS_LIB"standard"
BODY_TYPE"PLUMBING"
HDL_TAP"TRUE";
"B \NAC \NWC"1;
"S \NAC"
BN"10"126;
%"TAP"
"6","(-6025,2000)","0","standard","I314";
;
CDS_LIB"standard"
BODY_TYPE"PLUMBING"
HDL_TAP"TRUE";
"B \NAC \NWC"1;
"S \NAC"
BN"11"128;
%"TAP"
"6","(-6025,1900)","0","standard","I315";
;
CDS_LIB"standard"
BODY_TYPE"PLUMBING"
HDL_TAP"TRUE";
"B \NAC \NWC"1;
"S \NAC"
BN"12"130;
%"TAP"
"6","(-6025,1800)","0","standard","I316";
;
CDS_LIB"standard"
BODY_TYPE"PLUMBING"
HDL_TAP"TRUE";
"B \NAC \NWC"1;
"S \NAC"
BN"13"132;
%"TAP"
"6","(-6025,1700)","0","standard","I317";
;
CDS_LIB"standard"
BODY_TYPE"PLUMBING"
HDL_TAP"TRUE";
"B \NAC \NWC"1;
"S \NAC"
BN"14"134;
%"TAP"
"6","(-6025,1600)","0","standard","I318";
;
CDS_LIB"standard"
BODY_TYPE"PLUMBING"
HDL_TAP"TRUE";
"B \NAC \NWC"1;
"S \NAC"
BN"15"136;
%"TAP"
"6","(-5875,5650)","0","mstr_standard","I321";
;
CDS_LIB"mstr_standard"
BODY_TYPE"PLUMBING"
HDL_TAP"TRUE";
"B \NAC \NWC"7;
"S \NAC"
BN"0"66;
%"TAP"
"6","(-5875,5550)","0","mstr_standard","I322";
;
CDS_LIB"mstr_standard"
BODY_TYPE"PLUMBING"
HDL_TAP"TRUE";
"B \NAC \NWC"7;
"S \NAC"
BN"1"65;
%"TAP"
"6","(-5875,5450)","0","mstr_standard","I323";
;
CDS_LIB"mstr_standard"
BODY_TYPE"PLUMBING"
HDL_TAP"TRUE";
"B \NAC \NWC"7;
"S \NAC"
BN"2"64;
%"TAP"
"6","(-6025,5600)","0","mstr_standard","I324";
;
CDS_LIB"mstr_standard"
BODY_TYPE"PLUMBING"
HDL_TAP"TRUE";
"B \NAC \NWC"8;
"S \NAC"
BN"0"40;
%"TAP"
"6","(-6025,5500)","0","mstr_standard","I325";
;
CDS_LIB"mstr_standard"
BODY_TYPE"PLUMBING"
HDL_TAP"TRUE";
"B \NAC \NWC"8;
"S \NAC"
BN"1"52;
%"TAP"
"6","(-6025,5400)","0","standard","I326";
;
CDS_LIB"standard"
BODY_TYPE"PLUMBING"
HDL_TAP"TRUE";
"B \NAC \NWC"8;
"S \NAC"
BN"2"51;
%"TAP"
"6","(-5875,5150)","0","standard","I327";
;
CDS_LIB"standard"
BODY_TYPE"PLUMBING"
HDL_TAP"TRUE";
"B \NAC \NWC"7;
"S \NAC"
BN"5"61;
%"TAP"
"6","(-5875,5350)","0","standard","I328";
;
CDS_LIB"standard"
BODY_TYPE"PLUMBING"
HDL_TAP"TRUE";
"B \NAC \NWC"7;
"S \NAC"
BN"3"63;
%"TAP"
"6","(-5875,5250)","0","standard","I329";
;
CDS_LIB"standard"
BODY_TYPE"PLUMBING"
HDL_TAP"TRUE";
"B \NAC \NWC"7;
"S \NAC"
BN"4"62;
%"TAP"
"6","(-6025,5200)","0","standard","I330";
;
CDS_LIB"standard"
BODY_TYPE"PLUMBING"
HDL_TAP"TRUE";
"B \NAC \NWC"8;
"S \NAC"
BN"4"49;
%"TAP"
"6","(-6025,5300)","0","standard","I331";
;
CDS_LIB"standard"
BODY_TYPE"PLUMBING"
HDL_TAP"TRUE";
"B \NAC \NWC"8;
"S \NAC"
BN"3"50;
%"TAP"
"6","(-5875,5050)","0","standard","I332";
;
CDS_LIB"standard"
BODY_TYPE"PLUMBING"
HDL_TAP"TRUE";
"B \NAC \NWC"7;
"S \NAC"
BN"6"60;
%"TAP"
"6","(-5875,4850)","0","standard","I333";
;
CDS_LIB"standard"
BODY_TYPE"PLUMBING"
HDL_TAP"TRUE";
"B \NAC \NWC"7;
"S \NAC"
BN"8"58;
%"TAP"
"6","(-5875,4950)","0","standard","I334";
;
CDS_LIB"standard"
BODY_TYPE"PLUMBING"
HDL_TAP"TRUE";
"B \NAC \NWC"7;
"S \NAC"
BN"7"59;
%"TAP"
"6","(-6025,4900)","0","standard","I335";
;
CDS_LIB"standard"
BODY_TYPE"PLUMBING"
HDL_TAP"TRUE";
"B \NAC \NWC"8;
"S \NAC"
BN"7"46;
%"TAP"
"6","(-6025,5000)","0","standard","I336";
;
CDS_LIB"standard"
BODY_TYPE"PLUMBING"
HDL_TAP"TRUE";
"B \NAC \NWC"8;
"S \NAC"
BN"6"47;
%"TAP"
"6","(-6025,5100)","0","standard","I337";
;
CDS_LIB"standard"
BODY_TYPE"PLUMBING"
HDL_TAP"TRUE";
"B \NAC \NWC"8;
"S \NAC"
BN"5"48;
%"TAP"
"6","(-5875,4750)","0","standard","I338";
;
CDS_LIB"standard"
BODY_TYPE"PLUMBING"
HDL_TAP"TRUE";
"B \NAC \NWC"7;
"S \NAC"
BN"9"57;
%"TAP"
"6","(-5875,4650)","0","standard","I339";
;
CDS_LIB"standard"
BODY_TYPE"PLUMBING"
HDL_TAP"TRUE";
"B \NAC \NWC"7;
"S \NAC"
BN"10"56;
%"TAP"
"6","(-6025,4700)","0","standard","I340";
;
CDS_LIB"standard"
BODY_TYPE"PLUMBING"
HDL_TAP"TRUE";
"B \NAC \NWC"8;
"S \NAC"
BN"9"44;
%"TAP"
"6","(-6025,4800)","0","standard","I341";
;
CDS_LIB"standard"
BODY_TYPE"PLUMBING"
HDL_TAP"TRUE";
"B \NAC \NWC"8;
"S \NAC"
BN"8"45;
%"TAP"
"6","(-5875,4550)","0","standard","I342";
;
CDS_LIB"standard"
BODY_TYPE"PLUMBING"
HDL_TAP"TRUE";
"B \NAC \NWC"7;
"S \NAC"
BN"11"55;
%"TAP"
"6","(-5875,4350)","0","standard","I343";
;
CDS_LIB"standard"
BODY_TYPE"PLUMBING"
HDL_TAP"TRUE";
"B \NAC \NWC"7;
"S \NAC"
BN"13"53;
%"TAP"
"6","(-5875,4450)","0","standard","I344";
;
CDS_LIB"standard"
BODY_TYPE"PLUMBING"
HDL_TAP"TRUE";
"B \NAC \NWC"7;
"S \NAC"
BN"12"54;
%"TAP"
"6","(-6025,4400)","0","standard","I345";
;
CDS_LIB"standard"
BODY_TYPE"PLUMBING"
HDL_TAP"TRUE";
"B \NAC \NWC"8;
"S \NAC"
BN"12"41;
%"TAP"
"6","(-6025,4500)","0","standard","I346";
;
CDS_LIB"standard"
BODY_TYPE"PLUMBING"
HDL_TAP"TRUE";
"B \NAC \NWC"8;
"S \NAC"
BN"11"42;
%"TAP"
"6","(-6025,4600)","0","standard","I347";
;
CDS_LIB"standard"
BODY_TYPE"PLUMBING"
HDL_TAP"TRUE";
"B \NAC \NWC"8;
"S \NAC"
BN"10"43;
%"TAP"
"6","(-5875,4250)","0","standard","I348";
;
CDS_LIB"standard"
BODY_TYPE"PLUMBING"
HDL_TAP"TRUE";
"B \NAC \NWC"7;
"S \NAC"
BN"14"13;
%"TAP"
"6","(-5875,4150)","0","standard","I349";
;
CDS_LIB"standard"
BODY_TYPE"PLUMBING"
HDL_TAP"TRUE";
"B \NAC \NWC"7;
"S \NAC"
BN"15"15;
%"TAP"
"6","(-6025,4300)","0","standard","I350";
;
CDS_LIB"standard"
BODY_TYPE"PLUMBING"
HDL_TAP"TRUE";
"B \NAC \NWC"8;
"S \NAC"
BN"13"12;
%"TAP"
"6","(-6025,4100)","0","standard","I351";
;
CDS_LIB"standard"
BODY_TYPE"PLUMBING"
HDL_TAP"TRUE";
"B \NAC \NWC"8;
"S \NAC"
BN"15"11;
%"TAP"
"6","(-6025,4200)","0","standard","I352";
;
CDS_LIB"standard"
BODY_TYPE"PLUMBING"
HDL_TAP"TRUE";
"B \NAC \NWC"8;
"S \NAC"
BN"14"14;
END.
